(kicad_pcb
	(version 20260206)
	(generator "pcbnew")
	(generator_version "10.0")
	(general
		(thickness 1.6)
		(legacy_teardrops no)
	)
	(paper "A4")
	(title_block
		(title "v1-tray-backplane — T6M_tray_BP_c_1023_1120.brd")
		(comment 1 "Open CloudServer (Microsoft) / footprints 102-104 of 170")
	)
	(layers
		(0 "F.Cu" signal "TOP")
		(4 "In1.Cu" signal "GND")
		(6 "In2.Cu" signal "IN1")
		(8 "In3.Cu" signal "VCC")
		(10 "In4.Cu" signal "VCC1")
		(12 "In5.Cu" signal "IN2")
		(14 "In6.Cu" signal "GND1")
		(2 "B.Cu" signal "BOTTOM")
		(9 "F.Adhes" user "F.Adhesive")
		(11 "B.Adhes" user "B.Adhesive")
		(13 "F.Paste" user "Package Geometry/Pastemask Top")
		(15 "B.Paste" user "Package Geometry/Pastemask Bottom")
		(5 "F.SilkS" user "Ref Des/Silkscreen Top")
		(7 "B.SilkS" user "Ref Des/Silkscreen Bottom")
		(1 "F.Mask" user "Board Geometry/Soldermask Top")
		(3 "B.Mask" user "Board Geometry/Soldermask Bottom")
		(17 "Dwgs.User" user "User.Drawings")
		(19 "Cmts.User" user "User.Comments")
		(21 "Eco1.User" user "User.Eco1")
		(23 "Eco2.User" user "User.Eco2")
		(25 "Edge.Cuts" user "Board Geometry/Outline")
		(27 "Margin" user)
		(31 "F.CrtYd" user "Package Geometry/Place Bound Top")
		(29 "B.CrtYd" user "Package Geometry/Place Bound Bottom")
		(35 "F.Fab" user "Ref Des/Assembly Top")
		(33 "B.Fab" user "Ref Des/Assembly Bottom")
	)
	(footprint ""
		(layer "F.Cu")
		(at 379.9332 -35.433 90)
		(property "Reference" "L5"
			(at -21.4376 33.47847 90)
			(unlocked yes)
			(layer "F.SilkS")
			(effects
				(font
					(size 0.7874 0.5842)
					(thickness 0.1524)
				)
				(justify left)
			)
		)
		(property "Value" ""
			(at 0 0 90)
			(layer "F.Fab")
			(effects
				(font
					(size 1.27 1.27)
				)
			)
		)
		(duplicate_pad_numbers_are_jumpers no)
		(fp_line
			(start -1.905 -0.8636)
			(end 1.905 -0.8636)
			(stroke
				(width 0.1524)
				(type default)
			)
			(layer "F.SilkS")
		)
		(fp_line
			(start 1.905 0.8382)
			(end 1.905 -0.8382)
			(stroke
				(width 0.1524)
				(type default)
			)
			(layer "F.SilkS")
		)
		(fp_line
			(start 0.127 0.8382)
			(end 0.127 -0.8382)
			(stroke
				(width 0.1524)
				(type default)
			)
			(layer "F.SilkS")
		)
		(fp_line
			(start -0.127 0.8382)
			(end -0.127 -0.8382)
			(stroke
				(width 0.1524)
				(type default)
			)
			(layer "F.SilkS")
		)
		(fp_line
			(start -1.905 0.8382)
			(end -1.905 -0.8382)
			(stroke
				(width 0.1524)
				(type default)
			)
			(layer "F.SilkS")
		)
		(fp_line
			(start 1.905 0.8636)
			(end -1.905 0.8636)
			(stroke
				(width 0.1524)
				(type default)
			)
			(layer "F.SilkS")
		)
		(fp_rect
			(start -1.524 0.7112)
			(end 1.524 -0.7366)
			(stroke
				(width 0)
				(type default)
			)
			(fill no)
			(layer "F.CrtYd")
		)
		(pad "1" smd rect
			(at 0.94996 0 90)
			(size 1.1176 1.3716)
			(layers "F.Cu" "F.Mask" "F.Paste")
			(net "P3V3_10G_3_VCCT_L")
		)
		(pad "2" smd rect
			(at -0.94996 0 90)
			(size 1.1176 1.3716)
			(layers "F.Cu" "F.Mask" "F.Paste")
			(net "P3V3_10G_3_VCCT")
		)
	)
	(footprint ""
		(layer "F.Cu")
		(at 351.208848 -25.440894 180)
		(property "Reference" "R23"
			(at 58.940192 4.22656 0)
			(unlocked yes)
			(layer "F.SilkS")
			(effects
				(font
					(size 0.7874 0.5842)
					(thickness 0.1524)
				)
				(justify left)
			)
		)
		(property "Value" ""
			(at 0 0 180)
			(layer "F.Fab")
			(effects
				(font
					(size 1.27 1.27)
				)
			)
		)
		(duplicate_pad_numbers_are_jumpers no)
		(fp_line
			(start 0.7874 0.4064)
			(end -0.7874 0.4064)
			(stroke
				(width 0.1524)
				(type default)
			)
			(layer "F.SilkS")
		)
		(fp_line
			(start 0.7874 -0.4064)
			(end 0.7874 0.4064)
			(stroke
				(width 0.1524)
				(type default)
			)
			(layer "F.SilkS")
		)
		(fp_line
			(start -0.7874 0.4064)
			(end -0.7874 -0.4064)
			(stroke
				(width 0.1524)
				(type default)
			)
			(layer "F.SilkS")
		)
		(fp_line
			(start -0.7874 -0.4064)
			(end 0.7874 -0.4064)
			(stroke
				(width 0.1524)
				(type default)
			)
			(layer "F.SilkS")
		)
		(fp_poly
			(pts
				(xy -0.508 0.2794) (xy -0.508 0.2286) (xy -0.635 0.2286) (xy -0.635 -0.254) (xy -0.5334 -0.254)
				(xy -0.5334 -0.2794) (xy 0.5334 -0.2794) (xy 0.5334 -0.254) (xy 0.635 -0.254) (xy 0.635 0.254) (xy 0.5334 0.254)
				(xy 0.5334 0.2794)
			)
			(stroke
				(width 0)
				(type default)
			)
			(fill no)
			(layer "F.CrtYd")
		)
		(pad "1" smd rect
			(at 0.40005 0 180)
			(size 0.4572 0.508)
			(layers "F.Cu" "F.Mask" "F.Paste")
			(net "P3V3_BLAD2")
		)
		(pad "2" smd rect
			(at -0.40005 0 180)
			(size 0.4572 0.508)
			(layers "F.Cu" "F.Mask" "F.Paste")
			(net "ENET10G_3_SCL")
		)
	)
	(footprint ""
		(layer "F.Cu")
		(at 344.535252 -44.8691 180)
		(property "Reference" "J23"
			(at 1.111504 -18.424652 0)
			(unlocked yes)
			(layer "F.SilkS")
			(effects
				(font
					(size 0.7874 0.5842)
					(thickness 0.1524)
				)
				(justify left)
			)
		)
		(property "Value" ""
			(at 0 0 180)
			(layer "F.Fab")
			(effects
				(font
					(size 1.27 1.27)
				)
			)
		)
		(duplicate_pad_numbers_are_jumpers no)
		(fp_line
			(start 9.655048 10.80008)
			(end 9.655048 6.1976)
			(stroke
				(width 0.1524)
				(type default)
			)
			(layer "F.SilkS")
		)
		(fp_line
			(start 9.655048 2.9718)
			(end 9.655048 -9.9822)
			(stroke
				(width 0.1524)
				(type default)
			)
			(layer "F.SilkS")
		)
		(fp_line
			(start 9.655048 -12.827)
			(end 9.655048 -17.649952)
			(stroke
				(width 0.1524)
				(type default)
			)
			(layer "F.SilkS")
		)
		(fp_line
			(start 9.655048 -17.649952)
			(end -9.655048 -17.649952)
			(stroke
				(width 0.1524)
				(type default)
			)
			(layer "F.SilkS")
		)
		(fp_line
			(start -9.655048 10.80008)
			(end 9.655048 10.80008)
			(stroke
				(width 0.1524)
				(type default)
			)
			(layer "F.SilkS")
		)
		(fp_line
			(start -9.655048 5.969)
			(end -9.655048 10.80008)
			(stroke
				(width 0.1524)
				(type default)
			)
			(layer "F.SilkS")
		)
		(fp_line
			(start -9.655048 0)
			(end -9.655048 3.1496)
			(stroke
				(width 0.1524)
				(type default)
			)
			(layer "F.SilkS")
		)
		(fp_line
			(start -9.655048 -17.649952)
			(end -9.655556 -16.722344)
			(stroke
				(width 0.1524)
				(type default)
			)
			(layer "F.SilkS")
		)
		(fp_line
			(start -9.656826 -14.280642)
			(end -9.663684 -0.70612)
			(stroke
				(width 0.1524)
				(type default)
			)
			(layer "F.SilkS")
		)
		(fp_line
			(start -9.663684 -0.70612)
			(end -9.655048 0)
			(stroke
				(width 0.1524)
				(type default)
			)
			(layer "F.SilkS")
		)
		(fp_poly
			(pts
				(xy -9.3599 -6.4389) (xy -11.4681 -7.0739) (xy -11.4681 -5.8293)
			)
			(stroke
				(width 0)
				(type default)
			)
			(fill yes)
			(layer "F.SilkS")
		)
		(fp_poly
			(pts
				(xy -3.9116 -9.6139) (xy -3.9116 -8.1788) (xy 5.1816 -8.1788) (xy 5.1816 -9.6139)
			)
			(stroke
				(width 0)
				(type default)
			)
			(fill no)
			(layer "B.CrtYd")
		)
		(fp_poly
			(pts
				(xy -3.9116 -16.2052) (xy -3.9116 -14.7701) (xy 5.1562 -14.7701) (xy 5.1562 -16.2052)
			)
			(stroke
				(width 0)
				(type default)
			)
			(fill no)
			(layer "B.CrtYd")
		)
		(fp_poly
			(pts
				(xy -5.1816 -7.0993) (xy -5.1816 -5.6388) (xy 3.9116 -5.6388) (xy 3.9116 -7.0993)
			)
			(stroke
				(width 0)
				(type default)
			)
			(fill no)
			(layer "B.CrtYd")
		)
		(fp_poly
			(pts
				(xy -5.1816 -13.6652) (xy -5.1816 -12.2428) (xy 3.9116 -12.2428) (xy 3.9116 -13.6652)
			)
			(stroke
				(width 0)
				(type default)
			)
			(fill no)
			(layer "B.CrtYd")
		)
		(fp_poly
			(pts
				(arc
					(start 6.931406 4.569968)
					(mid 10.078466 4.569968)
					(end 6.931406 4.569968)
				)
			)
			(stroke
				(width 0)
				(type default)
			)
			(fill no)
			(layer "B.CrtYd")
		)
		(fp_poly
			(pts
				(arc
					(start 6.928104 -11.43)
					(mid 10.081768 -11.43)
					(end 6.928104 -11.43)
				)
			)
			(stroke
				(width 0)
				(type default)
			)
			(fill no)
			(layer "B.CrtYd")
		)
		(fp_poly
			(pts
				(arc
					(start 6.167628 -5.839968)
					(mid 9.322308 -5.839968)
					(end 6.167628 -5.839968)
				)
			)
			(stroke
				(width 0)
				(type default)
			)
			(fill no)
			(layer "B.CrtYd")
		)
		(fp_poly
			(pts
				(arc
					(start -9.320784 -9.139936)
					(mid -6.169152 -9.139936)
					(end -9.320784 -9.139936)
				)
			)
			(stroke
				(width 0)
				(type default)
			)
			(fill no)
			(layer "B.CrtYd")
		)
		(fp_poly
			(pts
				(arc
					(start -10.076434 4.569968)
					(mid -6.933438 4.569968)
					(end -10.076434 4.569968)
				)
			)
			(stroke
				(width 0)
				(type default)
			)
			(fill no)
			(layer "B.CrtYd")
		)
		(fp_poly
			(pts
				(arc
					(start -10.080498 -15.489936)
					(mid -6.929374 -15.489936)
					(end -10.080498 -15.489936)
				)
			)
			(stroke
				(width 0)
				(type default)
			)
			(fill no)
			(layer "B.CrtYd")
		)
		(fp_poly
			(pts
				(arc
					(start 3.838194 0)
					(mid 7.591806 0)
					(end 3.838194 0)
				)
			)
			(stroke
				(width 0)
				(type default)
			)
			(fill no)
			(layer "B.CrtYd")
		)
		(fp_poly
			(pts
				(arc
					(start -7.590028 0)
					(mid -3.839972 0)
					(end -7.590028 0)
				)
			)
			(stroke
				(width 0)
				(type default)
			)
			(fill no)
			(layer "B.CrtYd")
		)
		(fp_poly
			(pts
				(xy -9.655048 0) (xy -9.655048 10.80008) (xy 9.655048 10.80008) (xy 9.655048 -17.649952) (xy -9.655048 -17.649952)
				(xy -9.663684 -0.70612)
			)
			(stroke
				(width 0)
				(type default)
			)
			(fill no)
			(layer "F.CrtYd")
		)
		(fp_text user "B2"
			(at 10.244836 -14.285976 90)
			(unlocked yes)
			(layer "F.SilkS")
			(effects
				(font
					(size 0.7874 0.5842)
					(thickness 0.1524)
				)
				(justify left)
			)
		)
		(fp_text user "A7"
			(at 10.223246 -6.767576 90)
			(unlocked yes)
			(layer "F.SilkS")
			(effects
				(font
					(size 0.7874 0.5842)
					(thickness 0.1524)
				)
				(justify left)
			)
		)
		(fp_text user "A8"
			(at 10.223246 -9.993376 90)
			(unlocked yes)
			(layer "F.SilkS")
			(effects
				(font
					(size 0.7874 0.5842)
					(thickness 0.1524)
				)
				(justify left)
			)
		)
		(fp_text user "B1"
			(at 10.219436 -16.825976 90)
			(unlocked yes)
			(layer "F.SilkS")
			(effects
				(font
					(size 0.7874 0.5842)
					(thickness 0.1524)
				)
				(justify left)
			)
		)
		(fp_text user "A1"
			(at -10.1981 -5.788152 90)
			(unlocked yes)
			(layer "F.SilkS")
			(effects
				(font
					(size 0.7874 0.5842)
					(thickness 0.1524)
				)
				(justify left)
			)
		)
		(fp_text user "A2"
			(at -10.2743 -9.877552 90)
			(unlocked yes)
			(layer "F.SilkS")
			(effects
				(font
					(size 0.7874 0.5842)
					(thickness 0.1524)
				)
				(justify left)
			)
		)
		(fp_text user "B7"
			(at -10.2997 -18.132552 90)
			(unlocked yes)
			(layer "F.SilkS")
			(effects
				(font
					(size 0.7874 0.5842)
					(thickness 0.1524)
				)
				(justify left)
			)
		)
		(fp_text user "B8"
			(at -10.3251 -13.560552 90)
			(unlocked yes)
			(layer "F.SilkS")
			(effects
				(font
					(size 0.7874 0.5842)
					(thickness 0.1524)
				)
				(justify left)
			)
		)
		(fp_text user "A8"
			(at 5.601716 -8.899906 0)
			(unlocked yes)
			(layer "B.SilkS")
			(effects
				(font
					(size 0.7874 0.5842)
					(thickness 0.1524)
				)
				(justify left mirror)
			)
		)
		(fp_text user "B1"
			(at 5.525516 -15.507716 0)
			(unlocked yes)
			(layer "B.SilkS")
			(effects
				(font
					(size 0.7874 0.5842)
					(thickness 0.1524)
				)
				(justify left mirror)
			)
		)
		(fp_text user "B2"
			(at 4.696714 -13.018516 0)
			(unlocked yes)
			(layer "B.SilkS")
			(effects
				(font
					(size 0.7874 0.5842)
					(thickness 0.1524)
				)
				(justify left mirror)
			)
		)
		(fp_text user "A7"
			(at 4.468114 -6.4897 0)
			(unlocked yes)
			(layer "B.SilkS")
			(effects
				(font
					(size 0.7874 0.5842)
					(thickness 0.1524)
				)
				(justify left mirror)
			)
		)
		(fp_text user "A2"
			(at -5.597906 -8.855202 0)
			(unlocked yes)
			(layer "B.SilkS")
			(effects
				(font
					(size 0.7874 0.5842)
					(thickness 0.1524)
				)
				(justify left mirror)
			)
		)
		(fp_text user "B7"
			(at -5.674106 -15.685516 0)
			(unlocked yes)
			(layer "B.SilkS")
			(effects
				(font
					(size 0.7874 0.5842)
					(thickness 0.1524)
				)
				(justify left mirror)
			)
		)
		(fp_text user "B8"
			(at -6.782308 -12.942316 0)
			(unlocked yes)
			(layer "B.SilkS")
			(effects
				(font
					(size 0.7874 0.5842)
					(thickness 0.1524)
				)
				(justify left mirror)
			)
		)
		(fp_text user "A1"
			(at -6.909308 -6.309106 0)
			(unlocked yes)
			(layer "B.SilkS")
			(effects
				(font
					(size 0.7874 0.5842)
					(thickness 0.1524)
				)
				(justify left mirror)
			)
		)
		(pad "" np_thru_hole circle
			(at -5.715 0 180)
			(size 3.2512 3.2512)
			(drill 3.2512)
			(layers "*.Cu" "*.Mask")
			(clearance 0.381)
			(thermal_gap 0.381)
		)
		(pad "" np_thru_hole circle
			(at 5.715 0 180)
			(size 3.2512 3.2512)
			(drill 3.2512)
			(layers "*.Cu" "*.Mask")
			(clearance 0.381)
			(thermal_gap 0.381)
		)
		(pad "A1" thru_hole rect
			(at -4.445 -6.35 180)
			(size 1.2954 1.2954)
			(drill 0.889)
			(layers "*.Cu" "*.Mask")
			(remove_unused_layers no)
			(net "ENET1G_3_MDI0P")
			(clearance 0.0508)
			(thermal_gap 0.0508)
			(padstack
				(mode front_inner_back)
				(layer "Inner"
					(shape circle)
					(size 1.2954 1.2954)
					(clearance 0.0508)
				)
				(layer "B.Cu"
					(shape rect)
					(size 1.2954 1.2954)
					(clearance 0.0508)
				)
			)
		)
		(pad "A2" thru_hole circle
			(at -3.175 -8.89 180)
			(size 1.2954 1.2954)
			(drill 0.889)
			(layers "*.Cu" "*.Mask")
			(remove_unused_layers no)
			(net "ENET1G_3_MDI0N")
			(clearance 0.0508)
			(thermal_gap 0.0508)
		)
		(pad "A3" thru_hole circle
			(at -1.905 -6.35 180)
			(size 1.2954 1.2954)
			(drill 0.889)
			(layers "*.Cu" "*.Mask")
			(remove_unused_layers no)
			(net "ENET1G_3_MDI1P")
			(clearance 0.0508)
			(thermal_gap 0.0508)
		)
		(pad "A4" thru_hole circle
			(at -0.635 -8.89 180)
			(size 1.2954 1.2954)
			(drill 0.889)
			(layers "*.Cu" "*.Mask")
			(remove_unused_layers no)
			(net "ENET1G_3_MDI2P")
			(clearance 0.0508)
			(thermal_gap 0.0508)
		)
		(pad "A5" thru_hole circle
			(at 0.635 -6.35 180)
			(size 1.2954 1.2954)
			(drill 0.889)
			(layers "*.Cu" "*.Mask")
			(remove_unused_layers no)
			(net "ENET1G_3_MDI2N")
			(clearance 0.0508)
			(thermal_gap 0.0508)
		)
		(pad "A6" thru_hole circle
			(at 1.905 -8.89 180)
			(size 1.2954 1.2954)
			(drill 0.889)
			(layers "*.Cu" "*.Mask")
			(remove_unused_layers no)
			(net "ENET1G_3_MDI1N")
			(clearance 0.0508)
			(thermal_gap 0.0508)
		)
		(pad "A7" thru_hole circle
			(at 3.175 -6.35 180)
			(size 1.2954 1.2954)
			(drill 0.889)
			(layers "*.Cu" "*.Mask")
			(remove_unused_layers no)
			(net "ENET1G_3_MDI3P")
			(clearance 0.0508)
			(thermal_gap 0.0508)
		)
		(pad "A8" thru_hole circle
			(at 4.445 -8.89 180)
			(size 1.2954 1.2954)
			(drill 0.889)
			(layers "*.Cu" "*.Mask")
			(remove_unused_layers no)
			(net "ENET1G_3_MDI3N")
			(clearance 0.0508)
			(thermal_gap 0.0508)
		)
		(pad "B1" thru_hole circle
			(at 4.445 -15.489936 180)
			(size 1.2954 1.2954)
			(drill 0.889)
			(layers "*.Cu" "*.Mask")
			(remove_unused_layers no)
			(net "ENET1G_4_MDI0P")
			(clearance 0.0508)
			(thermal_gap 0.0508)
		)
		(pad "B2" thru_hole circle
			(at 3.175 -12.949936 180)
			(size 1.2954 1.2954)
			(drill 0.889)
			(layers "*.Cu" "*.Mask")
			(remove_unused_layers no)
			(net "ENET1G_4_MDI0N")
			(clearance 0.0508)
			(thermal_gap 0.0508)
		)
		(pad "B3" thru_hole circle
			(at 1.905 -15.489936 180)
			(size 1.2954 1.2954)
			(drill 0.889)
			(layers "*.Cu" "*.Mask")
			(remove_unused_layers no)
			(net "ENET1G_4_MDI1P")
			(clearance 0.0508)
			(thermal_gap 0.0508)
		)
		(pad "B4" thru_hole circle
			(at 0.635 -12.949936 180)
			(size 1.2954 1.2954)
			(drill 0.889)
			(layers "*.Cu" "*.Mask")
			(remove_unused_layers no)
			(net "ENET1G_4_MDI2P")
			(clearance 0.0508)
			(thermal_gap 0.0508)
		)
		(pad "B5" thru_hole circle
			(at -0.635 -15.489936 180)
			(size 1.2954 1.2954)
			(drill 0.889)
			(layers "*.Cu" "*.Mask")
			(remove_unused_layers no)
			(net "ENET1G_4_MDI2N")
			(clearance 0.0508)
			(thermal_gap 0.0508)
		)
		(pad "B6" thru_hole circle
			(at -1.905 -12.949936 180)
			(size 1.2954 1.2954)
			(drill 0.889)
			(layers "*.Cu" "*.Mask")
			(remove_unused_layers no)
			(net "ENET1G_4_MDI1N")
			(clearance 0.0508)
			(thermal_gap 0.0508)
		)
		(pad "B7" thru_hole circle
			(at -3.175 -15.489936 180)
			(size 1.2954 1.2954)
			(drill 0.889)
			(layers "*.Cu" "*.Mask")
			(remove_unused_layers no)
			(net "ENET1G_4_MDI3P")
			(clearance 0.0508)
			(thermal_gap 0.0508)
		)
		(pad "B8" thru_hole circle
			(at -4.445 -12.949936 180)
			(size 1.2954 1.2954)
			(drill 0.889)
			(layers "*.Cu" "*.Mask")
			(remove_unused_layers no)
			(net "ENET1G_4_MDI3N")
			(clearance 0.0508)
			(thermal_gap 0.0508)
		)
		(pad "G1" thru_hole circle
			(at -8.504936 -15.489936 180)
			(size 3.048 3.048)
			(drill 2.032)
			(layers "*.Cu" "*.Mask")
			(remove_unused_layers no)
			(net "GND")
			(clearance -0.254)
		)
		(pad "G2" thru_hole circle
			(at -7.744968 -9.139936 180)
			(size 3.048 3.048)
			(drill 2.032)
			(layers "*.Cu" "*.Mask")
			(remove_unused_layers no)
			(net "GND")
			(clearance -0.254)
		)
		(pad "G3" thru_hole circle
			(at -8.504936 4.569968 180)
			(size 3.048 3.048)
			(drill 2.032)
			(layers "*.Cu" "*.Mask")
			(remove_unused_layers no)
			(net "GND")
			(clearance -0.254)
		)
		(pad "G4" thru_hole circle
			(at 8.504936 4.569968 180)
			(size 3.048 3.048)
			(drill 2.032)
			(layers "*.Cu" "*.Mask")
			(remove_unused_layers no)
			(net "GND")
			(clearance -0.254)
		)
		(pad "G5" thru_hole circle
			(at 7.744968 -5.839968 180)
			(size 3.048 3.048)
			(drill 2.032)
			(layers "*.Cu" "*.Mask")
			(remove_unused_layers no)
			(net "GND")
			(clearance -0.254)
		)
		(pad "G6" thru_hole circle
			(at 8.504936 -11.43 180)
			(size 3.048 3.048)
			(drill 2.032)
			(layers "*.Cu" "*.Mask")
			(remove_unused_layers no)
			(net "GND")
			(clearance -0.254)
		)
		(zone
			(layers "F.Cu" "B.Cu" "In1.Cu" "In2.Cu" "In3.Cu" "In4.Cu" "In5.Cu" "In6.Cu")
			(hatch none 0.5)
			(connect_pads
				(clearance 0)
			)
			(min_thickness 0.25)
			(keepout
				(tracks not_allowed)
				(vias allowed)
				(pads allowed)
				(copperpour not_allowed)
				(footprints allowed)
			)
			(placement
				(enabled no)
				(sheetname "")
			)
			(fill
				(thermal_gap 0.5)
				(thermal_bridge_width 0.5)
				(island_removal_mode 0)
			)
			(polygon
				(pts
					(arc
						(start 340.854538 -44.8691)
						(mid 336.785966 -44.8691)
						(end 340.854538 -44.8691)
					)
				)
			)
		)
		(zone
			(layers "F.Cu" "B.Cu" "In1.Cu" "In2.Cu" "In3.Cu" "In4.Cu" "In5.Cu" "In6.Cu")
			(hatch none 0.5)
			(connect_pads
				(clearance 0)
			)
			(min_thickness 0.25)
			(keepout
				(tracks not_allowed)
				(vias allowed)
				(pads allowed)
				(copperpour not_allowed)
				(footprints allowed)
			)
			(placement
				(enabled no)
				(sheetname "")
			)
			(fill
				(thermal_gap 0.5)
				(thermal_bridge_width 0.5)
				(island_removal_mode 0)
			)
			(polygon
				(pts
					(arc
						(start 352.28276 -44.8691)
						(mid 348.217744 -44.8691)
						(end 352.28276 -44.8691)
					)
				)
			)
		)
	)
)
